(kicad_pcb
	(version 20260206)
	(generator "pcbnew")
	(generator_version "10.0")
	(general
		(thickness 1.6)
		(legacy_teardrops no)
	)
	(paper "A4")
	(title_block
		(title "pdpb — Lightning_PDPB_BRD.brd")
		(comment 1 "Lightning (Wiwynn / Facebook NVMe JBOF) / footprints 108-114 of 1140")
	)
	(layers
		(0 "F.Cu" signal "TOP")
		(4 "In1.Cu" signal "L2GND")
		(6 "In2.Cu" signal "L3")
		(8 "In3.Cu" signal "L4VCC")
		(10 "In4.Cu" signal "L5VCC")
		(12 "In5.Cu" signal "L6")
		(14 "In6.Cu" signal "L7GND")
		(2 "B.Cu" signal "BOTTOM")
		(9 "F.Adhes" user "F.Adhesive")
		(11 "B.Adhes" user "B.Adhesive")
		(13 "F.Paste" user "Package Geometry/Pastemask Top")
		(15 "B.Paste" user "Package Geometry/Pastemask Bottom")
		(5 "F.SilkS" user "Ref Des/Silkscreen Top")
		(7 "B.SilkS" user "Ref Des/Silkscreen Bottom")
		(1 "F.Mask" user "Board Geometry/Soldermask Top")
		(3 "B.Mask" user "Board Geometry/Soldermask Bottom")
		(17 "Dwgs.User" user "User.Drawings")
		(19 "Cmts.User" user "User.Comments")
		(21 "Eco1.User" user "User.Eco1")
		(23 "Eco2.User" user "User.Eco2")
		(25 "Edge.Cuts" user "Board Geometry/Outline")
		(27 "Margin" user)
		(31 "F.CrtYd" user "Package Geometry/Place Bound Top")
		(29 "B.CrtYd" user "Package Geometry/Place Bound Bottom")
		(35 "F.Fab" user "Ref Des/Assembly Top")
		(33 "B.Fab" user "Ref Des/Assembly Bottom")
	)
	(footprint ""
		(layer "F.Cu")
		(at 87.757 -225.806 90)
		(property "Reference" "R9517"
			(at 0 0 90)
			(layer "F.SilkS")
			(hide yes)
			(effects
				(font
					(size 1.27 1.27)
				)
			)
		)
		(property "Value" "4K7R2J-2-GP"
			(at 0.064008 -3.993896 90)
			(unlocked yes)
			(layer "F.Fab")
			(hide yes)
			(effects
				(font
					(size 1.016 1.016)
					(thickness 0.1524)
				)
			)
		)
		(property "Device Type" "R402H16"
			(at 0.064008 -5.517896 90)
			(unlocked yes)
			(layer "F.Fab")
			(hide yes)
			(effects
				(font
					(size 1.016 1.016)
					(thickness 0.1524)
				)
			)
		)
		(duplicate_pad_numbers_are_jumpers no)
		(fp_line
			(start 0.508 -0.9398)
			(end -0.508 -0.9398)
			(stroke
				(width 0.1524)
				(type default)
			)
			(layer "F.SilkS")
		)
		(fp_line
			(start -0.508 -0.9398)
			(end -0.508 0.9398)
			(stroke
				(width 0.1524)
				(type default)
			)
			(layer "F.SilkS")
		)
		(fp_rect
			(start -0.508 0.9398)
			(end 0.508 -0.9398)
			(stroke
				(width 0)
				(type default)
			)
			(fill no)
			(layer "F.CrtYd")
		)
		(fp_rect
			(start -0.508 0.9398)
			(end 0.508 -0.9398)
			(stroke
				(width 0)
				(type default)
			)
			(fill no)
			(layer "F.Fab")
		)
		(pad "1" smd custom
			(at 0 -0.4445 90)
			(size 0.1397 0.1397)
			(layers "F.Cu" "F.Mask" "F.Paste")
			(net "P3V3")
			(options
				(clearance outline)
				(anchor circle)
			)
			(primitives
				(gr_poly
					(pts
						(arc
							(start -0.1778 -0.2794)
							(mid -0.249642 -0.249642)
							(end -0.2794 -0.1778)
						)
						(arc
							(start -0.2794 0.1778)
							(mid -0.249642 0.249642)
							(end -0.1778 0.2794)
						)
						(arc
							(start 0.1778 0.2794)
							(mid 0.249642 0.249642)
							(end 0.2794 0.1778)
						)
						(arc
							(start 0.2794 -0.1778)
							(mid 0.249642 -0.249642)
							(end 0.1778 -0.2794)
						)
					)
					(width 0)
					(fill yes)
				)
			)
		)
		(pad "2" smd custom
			(at 0 0.4445 90)
			(size 0.1397 0.1397)
			(layers "F.Cu" "F.Mask" "F.Paste")
			(net "SSD12_CLK0_OE_N")
			(options
				(clearance outline)
				(anchor circle)
			)
			(primitives
				(gr_poly
					(pts
						(arc
							(start -0.1778 -0.2794)
							(mid -0.249642 -0.249642)
							(end -0.2794 -0.1778)
						)
						(arc
							(start -0.2794 0.1778)
							(mid -0.249642 0.249642)
							(end -0.1778 0.2794)
						)
						(arc
							(start 0.1778 0.2794)
							(mid 0.249642 0.249642)
							(end 0.2794 0.1778)
						)
						(arc
							(start 0.2794 -0.1778)
							(mid 0.249642 -0.249642)
							(end 0.1778 -0.2794)
						)
					)
					(width 0)
					(fill yes)
				)
			)
		)
	)
	(footprint ""
		(layer "F.Cu")
		(at 97.409 -198.755 90)
		(property "Reference" "C9366"
			(at 0 0 90)
			(layer "F.SilkS")
			(hide yes)
			(effects
				(font
					(size 1.27 1.27)
				)
			)
		)
		(property "Value" "SC1KP50V2KX-1GP"
			(at 1.1811 -2.7051 90)
			(unlocked yes)
			(layer "F.Fab")
			(hide yes)
			(effects
				(font
					(size 1.016 1.016)
					(thickness 0.1524)
				)
			)
		)
		(property "Device Type" "C402H22"
			(at 1.1811 -4.2291 90)
			(unlocked yes)
			(layer "F.Fab")
			(hide yes)
			(effects
				(font
					(size 1.016 1.016)
					(thickness 0.1524)
				)
			)
		)
		(duplicate_pad_numbers_are_jumpers no)
		(fp_rect
			(start -0.4318 0.9525)
			(end 0.4318 -0.9525)
			(stroke
				(width 0)
				(type default)
			)
			(fill no)
			(layer "F.CrtYd")
		)
		(fp_rect
			(start -0.4318 0.9525)
			(end 0.4318 -0.9525)
			(stroke
				(width 0)
				(type default)
			)
			(fill no)
			(layer "F.Fab")
		)
		(pad "1" smd custom
			(at 0 -0.4445 90)
			(size 0.1524 0.1524)
			(layers "F.Cu" "F.Mask" "F.Paste")
			(net "SSD4_CLK0_OE_R_N")
			(options
				(clearance outline)
				(anchor circle)
			)
			(primitives
				(gr_poly
					(pts
						(arc
							(start 0.3048 -0.2032)
							(mid 0.275042 -0.275042)
							(end 0.2032 -0.3048)
						)
						(arc
							(start -0.2032 -0.3048)
							(mid -0.275042 -0.275042)
							(end -0.3048 -0.2032)
						)
						(arc
							(start -0.3048 0.2032)
							(mid -0.275042 0.275042)
							(end -0.2032 0.3048)
						)
						(arc
							(start 0.2032 0.3048)
							(mid 0.275042 0.275042)
							(end 0.3048 0.2032)
						)
					)
					(width 0)
					(fill yes)
				)
			)
		)
		(pad "2" smd custom
			(at 0 0.4445 90)
			(size 0.1524 0.1524)
			(layers "F.Cu" "F.Mask" "F.Paste")
			(net "GND")
			(options
				(clearance outline)
				(anchor circle)
			)
			(primitives
				(gr_poly
					(pts
						(arc
							(start 0.3048 -0.2032)
							(mid 0.275042 -0.275042)
							(end 0.2032 -0.3048)
						)
						(arc
							(start -0.2032 -0.3048)
							(mid -0.275042 -0.275042)
							(end -0.3048 -0.2032)
						)
						(arc
							(start -0.3048 0.2032)
							(mid -0.275042 0.275042)
							(end -0.2032 0.3048)
						)
						(arc
							(start 0.2032 0.3048)
							(mid 0.275042 0.275042)
							(end 0.3048 0.2032)
						)
					)
					(width 0)
					(fill yes)
				)
			)
		)
	)
	(footprint ""
		(layer "F.Cu")
		(at 21.231606 -162.109658 180)
		(property "Reference" "R9925"
			(at 0 0 180)
			(layer "F.SilkS")
			(hide yes)
			(effects
				(font
					(size 1.27 1.27)
				)
			)
		)
		(property "Value" "47KR2J-2-GP"
			(at 0.064008 -3.993896 180)
			(unlocked yes)
			(layer "F.Fab")
			(hide yes)
			(effects
				(font
					(size 1.016 1.016)
					(thickness 0.1524)
				)
			)
		)
		(property "Device Type" "R402H16"
			(at 0.064008 -5.517896 180)
			(unlocked yes)
			(layer "F.Fab")
			(hide yes)
			(effects
				(font
					(size 1.016 1.016)
					(thickness 0.1524)
				)
			)
		)
		(duplicate_pad_numbers_are_jumpers no)
		(fp_line
			(start 0.508 -0.9398)
			(end -0.508 -0.9398)
			(stroke
				(width 0.1524)
				(type default)
			)
			(layer "F.SilkS")
		)
		(fp_line
			(start -0.508 -0.9398)
			(end -0.508 0.9398)
			(stroke
				(width 0.1524)
				(type default)
			)
			(layer "F.SilkS")
		)
		(fp_rect
			(start -0.508 0.9398)
			(end 0.508 -0.9398)
			(stroke
				(width 0)
				(type default)
			)
			(fill no)
			(layer "F.CrtYd")
		)
		(fp_rect
			(start -0.508 0.9398)
			(end 0.508 -0.9398)
			(stroke
				(width 0)
				(type default)
			)
			(fill no)
			(layer "F.Fab")
		)
		(pad "1" smd custom
			(at 0 -0.4445 180)
			(size 0.1397 0.1397)
			(layers "F.Cu" "F.Mask" "F.Paste")
			(net "P3V3")
			(options
				(clearance outline)
				(anchor circle)
			)
			(primitives
				(gr_poly
					(pts
						(arc
							(start -0.1778 -0.2794)
							(mid -0.249642 -0.249642)
							(end -0.2794 -0.1778)
						)
						(arc
							(start -0.2794 0.1778)
							(mid -0.249642 0.249642)
							(end -0.1778 0.2794)
						)
						(arc
							(start 0.1778 0.2794)
							(mid 0.249642 0.249642)
							(end 0.2794 0.1778)
						)
						(arc
							(start 0.2794 -0.1778)
							(mid 0.249642 -0.249642)
							(end 0.1778 -0.2794)
						)
					)
					(width 0)
					(fill yes)
				)
			)
		)
		(pad "2" smd custom
			(at 0 0.4445 180)
			(size 0.1397 0.1397)
			(layers "F.Cu" "F.Mask" "F.Paste")
			(net "ATTN_LED_DR13_N")
			(options
				(clearance outline)
				(anchor circle)
			)
			(primitives
				(gr_poly
					(pts
						(arc
							(start -0.1778 -0.2794)
							(mid -0.249642 -0.249642)
							(end -0.2794 -0.1778)
						)
						(arc
							(start -0.2794 0.1778)
							(mid -0.249642 0.249642)
							(end -0.1778 0.2794)
						)
						(arc
							(start 0.1778 0.2794)
							(mid 0.249642 0.249642)
							(end 0.2794 0.1778)
						)
						(arc
							(start 0.2794 -0.1778)
							(mid 0.249642 -0.249642)
							(end 0.1778 -0.2794)
						)
					)
					(width 0)
					(fill yes)
				)
			)
		)
	)
	(footprint ""
		(layer "F.Cu")
		(at 24.003 -52.197 -90)
		(property "Reference" "R9457"
			(at 0 0 270)
			(layer "F.SilkS")
			(hide yes)
			(effects
				(font
					(size 1.27 1.27)
				)
			)
		)
		(property "Value" "100R2J-2-GP"
			(at 0.064008 -3.993896 270)
			(unlocked yes)
			(layer "F.Fab")
			(hide yes)
			(effects
				(font
					(size 1.016 1.016)
					(thickness 0.1524)
				)
			)
		)
		(property "Device Type" "R402H14"
			(at 0.064008 -5.517896 270)
			(unlocked yes)
			(layer "F.Fab")
			(hide yes)
			(effects
				(font
					(size 1.016 1.016)
					(thickness 0.1524)
				)
			)
		)
		(duplicate_pad_numbers_are_jumpers no)
		(fp_line
			(start -0.508 -0.9398)
			(end -0.508 0.9398)
			(stroke
				(width 0.1524)
				(type default)
			)
			(layer "F.SilkS")
		)
		(fp_line
			(start 0.508 -0.9398)
			(end -0.508 -0.9398)
			(stroke
				(width 0.1524)
				(type default)
			)
			(layer "F.SilkS")
		)
		(fp_rect
			(start -0.508 0.9398)
			(end 0.508 -0.9398)
			(stroke
				(width 0)
				(type default)
			)
			(fill no)
			(layer "F.CrtYd")
		)
		(fp_rect
			(start -0.508 0.9398)
			(end 0.508 -0.9398)
			(stroke
				(width 0)
				(type default)
			)
			(fill no)
			(layer "F.Fab")
		)
		(pad "1" smd custom
			(at 0 -0.4445 270)
			(size 0.1397 0.1397)
			(layers "F.Cu" "F.Mask" "F.Paste")
			(net "P3V3")
			(options
				(clearance outline)
				(anchor circle)
			)
			(primitives
				(gr_poly
					(pts
						(arc
							(start -0.1778 -0.2794)
							(mid -0.249642 -0.249642)
							(end -0.2794 -0.1778)
						)
						(arc
							(start -0.2794 0.1778)
							(mid -0.249642 0.249642)
							(end -0.1778 0.2794)
						)
						(arc
							(start 0.1778 0.2794)
							(mid 0.249642 0.249642)
							(end 0.2794 0.1778)
						)
						(arc
							(start 0.2794 -0.1778)
							(mid 0.249642 -0.249642)
							(end 0.1778 -0.2794)
						)
					)
					(width 0)
					(fill yes)
				)
			)
		)
		(pad "2" smd custom
			(at 0 0.4445 270)
			(size 0.1397 0.1397)
			(layers "F.Cu" "F.Mask" "F.Paste")
			(net "DRV_ACT_14")
			(options
				(clearance outline)
				(anchor circle)
			)
			(primitives
				(gr_poly
					(pts
						(arc
							(start -0.1778 -0.2794)
							(mid -0.249642 -0.249642)
							(end -0.2794 -0.1778)
						)
						(arc
							(start -0.2794 0.1778)
							(mid -0.249642 0.249642)
							(end -0.1778 0.2794)
						)
						(arc
							(start 0.1778 0.2794)
							(mid 0.249642 0.249642)
							(end 0.2794 0.1778)
						)
						(arc
							(start 0.2794 -0.1778)
							(mid 0.249642 -0.249642)
							(end 0.1778 -0.2794)
						)
					)
					(width 0)
					(fill yes)
				)
			)
		)
	)
	(footprint ""
		(layer "F.Cu")
		(at 83.185 -151.638 90)
		(property "Reference" "SR1047"
			(at 0 0 90)
			(layer "F.SilkS")
			(hide yes)
			(effects
				(font
					(size 1.27 1.27)
				)
			)
		)
		(property "Value" "4K7R2F-GP"
			(at 0.064008 -3.993896 90)
			(unlocked yes)
			(layer "F.Fab")
			(hide yes)
			(effects
				(font
					(size 1.016 1.016)
					(thickness 0.1524)
				)
			)
		)
		(property "Device Type" "R402H16"
			(at 0.064008 -5.517896 90)
			(unlocked yes)
			(layer "F.Fab")
			(hide yes)
			(effects
				(font
					(size 1.016 1.016)
					(thickness 0.1524)
				)
			)
		)
		(duplicate_pad_numbers_are_jumpers no)
		(fp_line
			(start 0.508 -0.9398)
			(end -0.508 -0.9398)
			(stroke
				(width 0.1524)
				(type default)
			)
			(layer "F.SilkS")
		)
		(fp_line
			(start -0.508 -0.9398)
			(end -0.508 0.9398)
			(stroke
				(width 0.1524)
				(type default)
			)
			(layer "F.SilkS")
		)
		(fp_rect
			(start -0.508 0.9398)
			(end 0.508 -0.9398)
			(stroke
				(width 0)
				(type default)
			)
			(fill no)
			(layer "F.CrtYd")
		)
		(fp_rect
			(start -0.508 0.9398)
			(end 0.508 -0.9398)
			(stroke
				(width 0)
				(type default)
			)
			(fill no)
			(layer "F.Fab")
		)
		(pad "1" smd custom
			(at 0 -0.4445 90)
			(size 0.1397 0.1397)
			(layers "F.Cu" "F.Mask" "F.Paste")
			(net "I2C_SW_EU16_ADDRESS_A1")
			(options
				(clearance outline)
				(anchor circle)
			)
			(primitives
				(gr_poly
					(pts
						(arc
							(start -0.1778 -0.2794)
							(mid -0.249642 -0.249642)
							(end -0.2794 -0.1778)
						)
						(arc
							(start -0.2794 0.1778)
							(mid -0.249642 0.249642)
							(end -0.1778 0.2794)
						)
						(arc
							(start 0.1778 0.2794)
							(mid 0.249642 0.249642)
							(end 0.2794 0.1778)
						)
						(arc
							(start 0.2794 -0.1778)
							(mid 0.249642 -0.249642)
							(end 0.1778 -0.2794)
						)
					)
					(width 0)
					(fill yes)
				)
			)
		)
		(pad "2" smd custom
			(at 0 0.4445 90)
			(size 0.1397 0.1397)
			(layers "F.Cu" "F.Mask" "F.Paste")
			(net "GND")
			(options
				(clearance outline)
				(anchor circle)
			)
			(primitives
				(gr_poly
					(pts
						(arc
							(start -0.1778 -0.2794)
							(mid -0.249642 -0.249642)
							(end -0.2794 -0.1778)
						)
						(arc
							(start -0.2794 0.1778)
							(mid -0.249642 0.249642)
							(end -0.1778 0.2794)
						)
						(arc
							(start 0.1778 0.2794)
							(mid 0.249642 0.249642)
							(end 0.2794 0.1778)
						)
						(arc
							(start 0.2794 -0.1778)
							(mid 0.249642 -0.249642)
							(end 0.1778 -0.2794)
						)
					)
					(width 0)
					(fill yes)
				)
			)
		)
	)
	(footprint ""
		(layer "F.Cu")
		(at 24.13 -393.827 180)
		(property "Reference" "R572"
			(at 0 0 180)
			(layer "F.SilkS")
			(hide yes)
			(effects
				(font
					(size 1.27 1.27)
				)
			)
		)
		(property "Value" "300KR2F-GP"
			(at 0.064008 -3.993896 180)
			(unlocked yes)
			(layer "F.Fab")
			(hide yes)
			(effects
				(font
					(size 1.016 1.016)
					(thickness 0.1524)
				)
			)
		)
		(property "Device Type" "R402H16"
			(at 0.064008 -5.517896 180)
			(unlocked yes)
			(layer "F.Fab")
			(hide yes)
			(effects
				(font
					(size 1.016 1.016)
					(thickness 0.1524)
				)
			)
		)
		(duplicate_pad_numbers_are_jumpers no)
		(fp_line
			(start 0.508 -0.9398)
			(end -0.508 -0.9398)
			(stroke
				(width 0.1524)
				(type default)
			)
			(layer "F.SilkS")
		)
		(fp_line
			(start -0.508 -0.9398)
			(end -0.508 0.9398)
			(stroke
				(width 0.1524)
				(type default)
			)
			(layer "F.SilkS")
		)
		(fp_rect
			(start -0.508 0.9398)
			(end 0.508 -0.9398)
			(stroke
				(width 0)
				(type default)
			)
			(fill no)
			(layer "F.CrtYd")
		)
		(fp_rect
			(start -0.508 0.9398)
			(end 0.508 -0.9398)
			(stroke
				(width 0)
				(type default)
			)
			(fill no)
			(layer "F.Fab")
		)
		(pad "1" smd custom
			(at 0 -0.4445 180)
			(size 0.1397 0.1397)
			(layers "F.Cu" "F.Mask" "F.Paste")
			(net "SW_SSD6_N")
			(options
				(clearance outline)
				(anchor circle)
			)
			(primitives
				(gr_poly
					(pts
						(arc
							(start -0.1778 -0.2794)
							(mid -0.249642 -0.249642)
							(end -0.2794 -0.1778)
						)
						(arc
							(start -0.2794 0.1778)
							(mid -0.249642 0.249642)
							(end -0.1778 0.2794)
						)
						(arc
							(start 0.1778 0.2794)
							(mid 0.249642 0.249642)
							(end 0.2794 0.1778)
						)
						(arc
							(start 0.2794 -0.1778)
							(mid 0.249642 -0.249642)
							(end 0.1778 -0.2794)
						)
					)
					(width 0)
					(fill yes)
				)
			)
		)
		(pad "2" smd custom
			(at 0 0.4445 180)
			(size 0.1397 0.1397)
			(layers "F.Cu" "F.Mask" "F.Paste")
			(net "P12V")
			(options
				(clearance outline)
				(anchor circle)
			)
			(primitives
				(gr_poly
					(pts
						(arc
							(start -0.1778 -0.2794)
							(mid -0.249642 -0.249642)
							(end -0.2794 -0.1778)
						)
						(arc
							(start -0.2794 0.1778)
							(mid -0.249642 0.249642)
							(end -0.1778 0.2794)
						)
						(arc
							(start 0.1778 0.2794)
							(mid 0.249642 0.249642)
							(end 0.2794 0.1778)
						)
						(arc
							(start 0.2794 -0.1778)
							(mid 0.249642 -0.249642)
							(end 0.1778 -0.2794)
						)
					)
					(width 0)
					(fill yes)
				)
			)
		)
	)
	(footprint ""
		(layer "F.Cu")
		(at 26.416 -197.9676 -90)
		(property "Reference" "Q66"
			(at 0 0 270)
			(layer "F.SilkS")
			(hide yes)
			(effects
				(font
					(size 1.27 1.27)
				)
			)
		)
		(property "Value" "2N7002A-7-GP"
			(at 0.127 -8.9662 270)
			(unlocked yes)
			(layer "F.Fab")
			(hide yes)
			(effects
				(font
					(size 1.016 1.016)
					(thickness 0.1524)
				)
			)
		)
		(property "Device Type" "SOT23DGS2D4H48"
			(at 0.127 -10.4902 270)
			(unlocked yes)
			(layer "F.Fab")
			(hide yes)
			(effects
				(font
					(size 1.016 1.016)
					(thickness 0.1524)
				)
			)
		)
		(duplicate_pad_numbers_are_jumpers no)
		(fp_line
			(start -1.651 1.778)
			(end 1.651 1.778)
			(stroke
				(width 0.1524)
				(type default)
			)
			(layer "F.SilkS")
		)
		(fp_line
			(start 1.651 1.778)
			(end 1.651 -1.778)
			(stroke
				(width 0.1524)
				(type default)
			)
			(layer "F.SilkS")
		)
		(fp_line
			(start -1.651 -1.778)
			(end -1.651 1.778)
			(stroke
				(width 0.1524)
				(type default)
			)
			(layer "F.SilkS")
		)
		(fp_line
			(start 1.651 -1.778)
			(end -1.651 -1.778)
			(stroke
				(width 0.1524)
				(type default)
			)
			(layer "F.SilkS")
		)
		(fp_poly
			(pts
				(xy -1.778 1.8796) (xy -1.778 -1.8796) (xy 1.778 -1.8796) (xy 1.778 1.8796)
			)
			(stroke
				(width 0)
				(type default)
			)
			(fill no)
			(layer "F.CrtYd")
		)
		(fp_poly
			(pts
				(xy -1.778 1.8796) (xy -1.778 -1.8796) (xy 1.778 -1.8796) (xy 1.778 1.8796)
			)
			(stroke
				(width 0)
				(type default)
			)
			(fill no)
			(layer "F.Fab")
		)
		(pad "D" smd custom
			(at 0 -0.9525 270)
			(size 0.1905 0.1905)
			(layers "F.Cu" "F.Mask" "F.Paste")
			(net "P12V_MOST8_GATE")
			(options
				(clearance outline)
				(anchor circle)
			)
			(primitives
				(gr_poly
					(pts
						(arc
							(start -0.1778 0.5715)
							(mid -0.321484 0.511984)
							(end -0.381 0.3683)
						)
						(arc
							(start -0.381 -0.3683)
							(mid -0.321484 -0.511984)
							(end -0.1778 -0.5715)
						)
						(arc
							(start 0.1778 -0.5715)
							(mid 0.321484 -0.511984)
							(end 0.381 -0.3683)
						)
						(arc
							(start 0.381 0.3683)
							(mid 0.321484 0.511984)
							(end 0.1778 0.5715)
						)
					)
					(width 0)
					(fill yes)
				)
			)
		)
		(pad "G" smd custom
			(at -0.98425 0.9525 270)
			(size 0.1905 0.1905)
			(layers "F.Cu" "F.Mask" "F.Paste")
			(net "SSD8_PWREN_R")
			(options
				(clearance outline)
				(anchor circle)
			)
			(primitives
				(gr_poly
					(pts
						(arc
							(start -0.1778 0.5715)
							(mid -0.321484 0.511984)
							(end -0.381 0.3683)
						)
						(arc
							(start -0.381 -0.3683)
							(mid -0.321484 -0.511984)
							(end -0.1778 -0.5715)
						)
						(arc
							(start 0.1778 -0.5715)
							(mid 0.321484 -0.511984)
							(end 0.381 -0.3683)
						)
						(arc
							(start 0.381 0.3683)
							(mid 0.321484 0.511984)
							(end 0.1778 0.5715)
						)
					)
					(width 0)
					(fill yes)
				)
			)
		)
		(pad "S" smd custom
			(at 0.98425 0.9525 270)
			(size 0.1905 0.1905)
			(layers "F.Cu" "F.Mask" "F.Paste")
			(net "GND")
			(options
				(clearance outline)
				(anchor circle)
			)
			(primitives
				(gr_poly
					(pts
						(arc
							(start -0.1778 0.5715)
							(mid -0.321484 0.511984)
							(end -0.381 0.3683)
						)
						(arc
							(start -0.381 -0.3683)
							(mid -0.321484 -0.511984)
							(end -0.1778 -0.5715)
						)
						(arc
							(start 0.1778 -0.5715)
							(mid 0.321484 -0.511984)
							(end 0.381 -0.3683)
						)
						(arc
							(start 0.381 0.3683)
							(mid 0.321484 0.511984)
							(end 0.1778 0.5715)
						)
					)
					(width 0)
					(fill yes)
				)
			)
		)
	)
)
